# T6G (Grand Teton) — schematic netlist excerpt (pin names and nets, part order shuffled) for the footprints in the layout excerpt that follows; sources: Cadence DE-HDL packaged netlist, KiCad conversion of 04192023_DAF0TMB3IC0_F0TG_MB_C_brd_V02_OCP.brd

C682  Q_CAP_DIFFBUS  DIFF BUS_0.22UF 6.3V 20% X6S  pkg C0201  page 67 : \1\ = P5E_CPU1_G1_TX_C_DN<13> ; \2\ = P5E_CPU1_G1_TX_DN<13>
C348  Q_CAP  0.1UF 25V 10% EMPTY  pkg 0402  page 192 : A = PVDD33_S5_EN ; B = GND
R61  Q_RES  49.9 1% CHIP  pkg 0402LF  page 200 : A = SVID_PVDDCR_CPU1_P0_SVTO ; B = SVID_PVDDCR_CPU1_P0_SVTO_R

(kicad_pcb
	(version 20260206)
	(generator "pcbnew")
	(generator_version "10.0")
	(general
		(thickness 1.6)
		(legacy_teardrops no)
	)
	(paper "A4")
	(title_block
		(title "04192023_DAF0TMB3IC0_F0TG_MB_C_brd_V02_OCP.brd")
		(comment 1 "Grand Teton / footprints 1415-1417 of 8354")
	)
	(layers
		(0 "F.Cu" signal "TOP")
		(4 "In1.Cu" signal "GND")
		(6 "In2.Cu" signal "IN1")
		(8 "In3.Cu" signal "GND1")
		(10 "In4.Cu" signal "IN2")
		(12 "In5.Cu" signal "GND2")
		(14 "In6.Cu" signal "IN3")
		(16 "In7.Cu" signal "GND3")
		(18 "In8.Cu" signal "VCC")
		(20 "In9.Cu" signal "VCC1")
		(22 "In10.Cu" signal "GND4")
		(24 "In11.Cu" signal "IN4")
		(26 "In12.Cu" signal "GND5")
		(28 "In13.Cu" signal "IN5")
		(30 "In14.Cu" signal "GND6")
		(32 "In15.Cu" signal "IN6")
		(34 "In16.Cu" signal "GND7")
		(2 "B.Cu" signal "BOTTOM")
		(9 "F.Adhes" user "F.Adhesive")
		(11 "B.Adhes" user "B.Adhesive")
		(13 "F.Paste" user "Package Geometry/Pastemask Top")
		(15 "B.Paste" user "Package Geometry/Pastemask Bottom")
		(5 "F.SilkS" user "Ref Des/Silkscreen Top")
		(7 "B.SilkS" user "Ref Des/Silkscreen Bottom")
		(1 "F.Mask" user "Board Geometry/Soldermask Top")
		(3 "B.Mask" user "Board Geometry/Soldermask Bottom")
		(17 "Dwgs.User" user "User.Drawings")
		(19 "Cmts.User" user "User.Comments")
		(21 "Eco1.User" user "User.Eco1")
		(23 "Eco2.User" user "User.Eco2")
		(25 "Edge.Cuts" user "Board Geometry/Outline")
		(27 "Margin" user)
		(31 "F.CrtYd" user "Package Geometry/Place Bound Top")
		(29 "B.CrtYd" user "Package Geometry/Place Bound Bottom")
		(35 "F.Fab" user "Ref Des/Assembly Top")
		(33 "B.Fab" user "Ref Des/Assembly Bottom")
	)
	(footprint ""
		(layer "F.Cu")
		(at 204.792834 -343.404952)
		(property "Reference" "C348"
			(at 0 0 0)
			(layer "F.SilkS")
			(hide yes)
			(effects
				(font
					(size 1.27 1.27)
				)
			)
		)
		(property "Value" ""
			(at 0 0 0)
			(layer "F.Fab")
			(effects
				(font
					(size 1.27 1.27)
				)
			)
		)
		(duplicate_pad_numbers_are_jumpers no)
		(fp_line
			(start -0.7874 -0.4064)
			(end 0.7874 -0.4064)
			(stroke
				(width 0.1524)
				(type default)
			)
			(layer "F.SilkS")
		)
		(fp_line
			(start -0.7874 0.4064)
			(end -0.7874 -0.4064)
			(stroke
				(width 0.1524)
				(type default)
			)
			(layer "F.SilkS")
		)
		(fp_line
			(start 0.7874 -0.4064)
			(end 0.7874 0.4064)
			(stroke
				(width 0.1524)
				(type default)
			)
			(layer "F.SilkS")
		)
		(fp_line
			(start 0.7874 0.4064)
			(end -0.7874 0.4064)
			(stroke
				(width 0.1524)
				(type default)
			)
			(layer "F.SilkS")
		)
		(fp_line
			(start -0.67945 -0.305054)
			(end -0.12065 -0.305054)
			(stroke
				(width 0.1)
				(type default)
			)
			(layer "F.Fab")
		)
		(fp_line
			(start -0.67945 0.3048)
			(end -0.67945 -0.305054)
			(stroke
				(width 0.1)
				(type default)
			)
			(layer "F.Fab")
		)
		(fp_line
			(start -0.12065 -0.305054)
			(end -0.12065 -0.2794)
			(stroke
				(width 0.1)
				(type default)
			)
			(layer "F.Fab")
		)
		(fp_line
			(start -0.12065 -0.2794)
			(end 0.12065 -0.2794)
			(stroke
				(width 0.1)
				(type default)
			)
			(layer "F.Fab")
		)
		(fp_line
			(start -0.12065 0.2794)
			(end -0.12065 0.3048)
			(stroke
				(width 0.1)
				(type default)
			)
			(layer "F.Fab")
		)
		(fp_line
			(start -0.12065 0.3048)
			(end -0.67945 0.3048)
			(stroke
				(width 0.1)
				(type default)
			)
			(layer "F.Fab")
		)
		(fp_line
			(start 0.120396 0.2794)
			(end -0.12065 0.2794)
			(stroke
				(width 0.1)
				(type default)
			)
			(layer "F.Fab")
		)
		(fp_line
			(start 0.120396 0.3048)
			(end 0.120396 0.2794)
			(stroke
				(width 0.1)
				(type default)
			)
			(layer "F.Fab")
		)
		(fp_line
			(start 0.12065 -0.3048)
			(end 0.67945 -0.3048)
			(stroke
				(width 0.1)
				(type default)
			)
			(layer "F.Fab")
		)
		(fp_line
			(start 0.12065 -0.2794)
			(end 0.12065 -0.3048)
			(stroke
				(width 0.1)
				(type default)
			)
			(layer "F.Fab")
		)
		(fp_line
			(start 0.67945 -0.3048)
			(end 0.67945 0.3048)
			(stroke
				(width 0.1)
				(type default)
			)
			(layer "F.Fab")
		)
		(fp_line
			(start 0.67945 0.3048)
			(end 0.120396 0.3048)
			(stroke
				(width 0.1)
				(type default)
			)
			(layer "F.Fab")
		)
		(pad "1" smd circle
			(at -0.40005 0)
			(size 0 0)
			(layers "F.Cu" "F.Mask" "F.Paste")
			(net "PVDD33_S5_EN")
		)
		(pad "2" smd circle
			(at 0.40005 0)
			(size 0 0)
			(layers "F.Cu" "F.Mask" "F.Paste")
			(net "GND")
		)
	)
	(footprint ""
		(layer "F.Cu")
		(at 304.419 -355.854)
		(property "Reference" "R61"
			(at 0 0 0)
			(layer "F.SilkS")
			(hide yes)
			(effects
				(font
					(size 1.27 1.27)
				)
			)
		)
		(property "Value" ""
			(at 0 0 0)
			(layer "F.Fab")
			(effects
				(font
					(size 1.27 1.27)
				)
			)
		)
		(duplicate_pad_numbers_are_jumpers no)
		(fp_line
			(start -0.7874 -0.4064)
			(end 0.7874 -0.4064)
			(stroke
				(width 0.1524)
				(type default)
			)
			(layer "F.SilkS")
		)
		(fp_line
			(start -0.7874 0.4064)
			(end -0.7874 -0.4064)
			(stroke
				(width 0.1524)
				(type default)
			)
			(layer "F.SilkS")
		)
		(fp_line
			(start 0.7874 -0.4064)
			(end 0.7874 0.4064)
			(stroke
				(width 0.1524)
				(type default)
			)
			(layer "F.SilkS")
		)
		(fp_line
			(start 0.7874 0.4064)
			(end -0.7874 0.4064)
			(stroke
				(width 0.1524)
				(type default)
			)
			(layer "F.SilkS")
		)
		(fp_line
			(start -0.67945 -0.305054)
			(end -0.12065 -0.305054)
			(stroke
				(width 0.1)
				(type default)
			)
			(layer "F.Fab")
		)
		(fp_line
			(start -0.67945 0.3048)
			(end -0.67945 -0.305054)
			(stroke
				(width 0.1)
				(type default)
			)
			(layer "F.Fab")
		)
		(fp_line
			(start -0.12065 -0.305054)
			(end -0.12065 -0.2794)
			(stroke
				(width 0.1)
				(type default)
			)
			(layer "F.Fab")
		)
		(fp_line
			(start -0.12065 -0.2794)
			(end 0.12065 -0.2794)
			(stroke
				(width 0.1)
				(type default)
			)
			(layer "F.Fab")
		)
		(fp_line
			(start -0.12065 0.2794)
			(end -0.12065 0.3048)
			(stroke
				(width 0.1)
				(type default)
			)
			(layer "F.Fab")
		)
		(fp_line
			(start -0.12065 0.3048)
			(end -0.67945 0.3048)
			(stroke
				(width 0.1)
				(type default)
			)
			(layer "F.Fab")
		)
		(fp_line
			(start 0.120396 0.2794)
			(end -0.12065 0.2794)
			(stroke
				(width 0.1)
				(type default)
			)
			(layer "F.Fab")
		)
		(fp_line
			(start 0.120396 0.3048)
			(end 0.120396 0.2794)
			(stroke
				(width 0.1)
				(type default)
			)
			(layer "F.Fab")
		)
		(fp_line
			(start 0.12065 -0.3048)
			(end 0.67945 -0.3048)
			(stroke
				(width 0.1)
				(type default)
			)
			(layer "F.Fab")
		)
		(fp_line
			(start 0.12065 -0.2794)
			(end 0.12065 -0.3048)
			(stroke
				(width 0.1)
				(type default)
			)
			(layer "F.Fab")
		)
		(fp_line
			(start 0.67945 -0.3048)
			(end 0.67945 0.3048)
			(stroke
				(width 0.1)
				(type default)
			)
			(layer "F.Fab")
		)
		(fp_line
			(start 0.67945 0.3048)
			(end 0.120396 0.3048)
			(stroke
				(width 0.1)
				(type default)
			)
			(layer "F.Fab")
		)
		(pad "1" smd circle
			(at -0.40005 0)
			(size 0 0)
			(layers "F.Cu" "F.Mask" "F.Paste")
			(net "SVID_PVDDCR_CPU1_P0_SVTO")
		)
		(pad "2" smd circle
			(at 0.40005 0)
			(size 0 0)
			(layers "F.Cu" "F.Mask" "F.Paste")
			(net "SVID_PVDDCR_CPU1_P0_SVTO_R")
		)
	)
	(footprint ""
		(layer "F.Cu")
		(at 21.096478 -16.099536 90)
		(property "Reference" "C682"
			(at 0 0 90)
			(layer "F.SilkS")
			(hide yes)
			(effects
				(font
					(size 1.27 1.27)
				)
			)
		)
		(property "Value" ""
			(at 0 0 90)
			(layer "F.Fab")
			(effects
				(font
					(size 1.27 1.27)
				)
			)
		)
		(duplicate_pad_numbers_are_jumpers no)
		(fp_line
			(start 0.299974 -0.150114)
			(end 0.299974 0.150114)
			(stroke
				(width 0.1)
				(type default)
			)
			(layer "F.Fab")
		)
		(fp_line
			(start -0.299974 -0.150114)
			(end 0.299974 -0.150114)
			(stroke
				(width 0.1)
				(type default)
			)
			(layer "F.Fab")
		)
		(fp_line
			(start 0.299974 0.150114)
			(end -0.299974 0.150114)
			(stroke
				(width 0.1)
				(type default)
			)
			(layer "F.Fab")
		)
		(fp_line
			(start -0.299974 0.150114)
			(end -0.299974 -0.150114)
			(stroke
				(width 0.1)
				(type default)
			)
			(layer "F.Fab")
		)
		(pad "1" smd rect
			(at -0.2667 0 90)
			(size 0.3048 0.381)
			(layers "F.Cu" "F.Mask" "F.Paste")
			(net "P5E_CPU1_G1_TX_C_DN<13>")
		)
		(pad "2" smd rect
			(at 0.2667 0 90)
			(size 0.3048 0.381)
			(layers "F.Cu" "F.Mask" "F.Paste")
			(net "P5E_CPU1_G1_TX_DN<13>")
		)
	)
)
